(kicad_pcb
	(version 20260206)
	(generator "pcbnew")
	(generator_version "10.0")
	(general
		(thickness 1.6)
		(legacy_teardrops no)
	)
	(paper "A4")
	(title_block
		(title "12092022_DA0F0TMDCD0_F0T_Management_Board_D_brd_V3_OCP.brd")
		(comment 1 "Grand Teton / footprints 268-274 of 1440")
	)
	(layers
		(0 "F.Cu" signal "TOP")
		(4 "In1.Cu" signal "GND")
		(6 "In2.Cu" signal "IN1")
		(8 "In3.Cu" signal "GND1")
		(10 "In4.Cu" signal "IN2")
		(12 "In5.Cu" signal "VCC")
		(14 "In6.Cu" signal "VCC1")
		(16 "In7.Cu" signal "IN3")
		(18 "In8.Cu" signal "GND2")
		(20 "In9.Cu" signal "IN4")
		(22 "In10.Cu" signal "GND3")
		(2 "B.Cu" signal "BOTTOM")
		(9 "F.Adhes" user "F.Adhesive")
		(11 "B.Adhes" user "B.Adhesive")
		(13 "F.Paste" user "Package Geometry/Pastemask Top")
		(15 "B.Paste" user "Package Geometry/Pastemask Bottom")
		(5 "F.SilkS" user "Ref Des/Silkscreen Top")
		(7 "B.SilkS" user "Ref Des/Silkscreen Bottom")
		(1 "F.Mask" user "Board Geometry/Soldermask Top")
		(3 "B.Mask" user "Board Geometry/Soldermask Bottom")
		(17 "Dwgs.User" user "User.Drawings")
		(19 "Cmts.User" user "User.Comments")
		(21 "Eco1.User" user "User.Eco1")
		(23 "Eco2.User" user "User.Eco2")
		(25 "Edge.Cuts" user "Board Geometry/Outline")
		(27 "Margin" user)
		(31 "F.CrtYd" user "Package Geometry/Place Bound Top")
		(29 "B.CrtYd" user "Package Geometry/Place Bound Bottom")
		(35 "F.Fab" user "Ref Des/Assembly Top")
		(33 "B.Fab" user "Ref Des/Assembly Bottom")
	)
	(footprint ""
		(layer "F.Cu")
		(at 68.189094 -92.61094)
		(property "Reference" "R503"
			(at 0 0 0)
			(layer "F.SilkS")
			(hide yes)
			(effects
				(font
					(size 1.27 1.27)
				)
			)
		)
		(property "Value" ""
			(at 0 0 0)
			(layer "F.Fab")
			(effects
				(font
					(size 1.27 1.27)
				)
			)
		)
		(duplicate_pad_numbers_are_jumpers no)
		(fp_line
			(start -0.7874 -0.4064)
			(end 0.7874 -0.4064)
			(stroke
				(width 0.1524)
				(type default)
			)
			(layer "F.SilkS")
		)
		(fp_line
			(start -0.7874 0.4064)
			(end -0.7874 -0.4064)
			(stroke
				(width 0.1524)
				(type default)
			)
			(layer "F.SilkS")
		)
		(fp_line
			(start 0.7874 -0.4064)
			(end 0.7874 0.4064)
			(stroke
				(width 0.1524)
				(type default)
			)
			(layer "F.SilkS")
		)
		(fp_line
			(start 0.7874 0.4064)
			(end -0.7874 0.4064)
			(stroke
				(width 0.1524)
				(type default)
			)
			(layer "F.SilkS")
		)
		(fp_line
			(start -0.67945 -0.305054)
			(end -0.12065 -0.305054)
			(stroke
				(width 0.1)
				(type default)
			)
			(layer "F.Fab")
		)
		(fp_line
			(start -0.67945 0.3048)
			(end -0.67945 -0.305054)
			(stroke
				(width 0.1)
				(type default)
			)
			(layer "F.Fab")
		)
		(fp_line
			(start -0.12065 -0.305054)
			(end -0.12065 -0.2794)
			(stroke
				(width 0.1)
				(type default)
			)
			(layer "F.Fab")
		)
		(fp_line
			(start -0.12065 -0.2794)
			(end 0.12065 -0.2794)
			(stroke
				(width 0.1)
				(type default)
			)
			(layer "F.Fab")
		)
		(fp_line
			(start -0.12065 0.2794)
			(end -0.12065 0.3048)
			(stroke
				(width 0.1)
				(type default)
			)
			(layer "F.Fab")
		)
		(fp_line
			(start -0.12065 0.3048)
			(end -0.67945 0.3048)
			(stroke
				(width 0.1)
				(type default)
			)
			(layer "F.Fab")
		)
		(fp_line
			(start 0.120396 0.2794)
			(end -0.12065 0.2794)
			(stroke
				(width 0.1)
				(type default)
			)
			(layer "F.Fab")
		)
		(fp_line
			(start 0.120396 0.3048)
			(end 0.120396 0.2794)
			(stroke
				(width 0.1)
				(type default)
			)
			(layer "F.Fab")
		)
		(fp_line
			(start 0.12065 -0.3048)
			(end 0.67945 -0.3048)
			(stroke
				(width 0.1)
				(type default)
			)
			(layer "F.Fab")
		)
		(fp_line
			(start 0.12065 -0.2794)
			(end 0.12065 -0.3048)
			(stroke
				(width 0.1)
				(type default)
			)
			(layer "F.Fab")
		)
		(fp_line
			(start 0.67945 -0.3048)
			(end 0.67945 0.3048)
			(stroke
				(width 0.1)
				(type default)
			)
			(layer "F.Fab")
		)
		(fp_line
			(start 0.67945 0.3048)
			(end 0.120396 0.3048)
			(stroke
				(width 0.1)
				(type default)
			)
			(layer "F.Fab")
		)
		(pad "1" smd circle
			(at -0.40005 0)
			(size 0 0)
			(layers "F.Cu" "F.Mask" "F.Paste")
			(net "RST_PLTRST_TPM_N")
		)
		(pad "2" smd circle
			(at 0.40005 0)
			(size 0 0)
			(layers "F.Cu" "F.Mask" "F.Paste")
			(net "RST_PLTRST_N")
		)
	)
	(footprint ""
		(layer "F.Cu")
		(at 36.1442 -70.4088 -90)
		(property "Reference" "C228"
			(at 0 0 270)
			(layer "F.SilkS")
			(hide yes)
			(effects
				(font
					(size 1.27 1.27)
				)
			)
		)
		(property "Value" ""
			(at 0 0 270)
			(layer "F.Fab")
			(effects
				(font
					(size 1.27 1.27)
				)
			)
		)
		(duplicate_pad_numbers_are_jumpers no)
		(fp_line
			(start -0.7874 0.4064)
			(end -0.7874 -0.4064)
			(stroke
				(width 0.1524)
				(type default)
			)
			(layer "F.SilkS")
		)
		(fp_line
			(start 0.7874 0.4064)
			(end -0.7874 0.4064)
			(stroke
				(width 0.1524)
				(type default)
			)
			(layer "F.SilkS")
		)
		(fp_line
			(start -0.7874 -0.4064)
			(end 0.7874 -0.4064)
			(stroke
				(width 0.1524)
				(type default)
			)
			(layer "F.SilkS")
		)
		(fp_line
			(start 0.7874 -0.4064)
			(end 0.7874 0.4064)
			(stroke
				(width 0.1524)
				(type default)
			)
			(layer "F.SilkS")
		)
		(fp_line
			(start -0.67945 0.3048)
			(end -0.67945 -0.305054)
			(stroke
				(width 0.1)
				(type default)
			)
			(layer "F.Fab")
		)
		(fp_line
			(start -0.12065 0.3048)
			(end -0.67945 0.3048)
			(stroke
				(width 0.1)
				(type default)
			)
			(layer "F.Fab")
		)
		(fp_line
			(start 0.120396 0.3048)
			(end 0.120396 0.2794)
			(stroke
				(width 0.1)
				(type default)
			)
			(layer "F.Fab")
		)
		(fp_line
			(start 0.67945 0.3048)
			(end 0.120396 0.3048)
			(stroke
				(width 0.1)
				(type default)
			)
			(layer "F.Fab")
		)
		(fp_line
			(start -0.12065 0.2794)
			(end -0.12065 0.3048)
			(stroke
				(width 0.1)
				(type default)
			)
			(layer "F.Fab")
		)
		(fp_line
			(start 0.120396 0.2794)
			(end -0.12065 0.2794)
			(stroke
				(width 0.1)
				(type default)
			)
			(layer "F.Fab")
		)
		(fp_line
			(start -0.12065 -0.2794)
			(end 0.12065 -0.2794)
			(stroke
				(width 0.1)
				(type default)
			)
			(layer "F.Fab")
		)
		(fp_line
			(start 0.12065 -0.2794)
			(end 0.12065 -0.3048)
			(stroke
				(width 0.1)
				(type default)
			)
			(layer "F.Fab")
		)
		(fp_line
			(start 0.12065 -0.3048)
			(end 0.67945 -0.3048)
			(stroke
				(width 0.1)
				(type default)
			)
			(layer "F.Fab")
		)
		(fp_line
			(start 0.67945 -0.3048)
			(end 0.67945 0.3048)
			(stroke
				(width 0.1)
				(type default)
			)
			(layer "F.Fab")
		)
		(fp_line
			(start -0.67945 -0.305054)
			(end -0.12065 -0.305054)
			(stroke
				(width 0.1)
				(type default)
			)
			(layer "F.Fab")
		)
		(fp_line
			(start -0.12065 -0.305054)
			(end -0.12065 -0.2794)
			(stroke
				(width 0.1)
				(type default)
			)
			(layer "F.Fab")
		)
		(pad "1" smd circle
			(at -0.40005 0 270)
			(size 0 0)
			(layers "F.Cu" "F.Mask" "F.Paste")
			(net "P3V3_AUX")
		)
		(pad "2" smd circle
			(at 0.40005 0 270)
			(size 0 0)
			(layers "F.Cu" "F.Mask" "F.Paste")
			(net "GND")
		)
	)
	(footprint ""
		(layer "F.Cu")
		(at 47.879 -67.818 180)
		(property "Reference" "R319"
			(at 0 0 180)
			(layer "F.SilkS")
			(hide yes)
			(effects
				(font
					(size 1.27 1.27)
				)
			)
		)
		(property "Value" ""
			(at 0 0 180)
			(layer "F.Fab")
			(effects
				(font
					(size 1.27 1.27)
				)
			)
		)
		(duplicate_pad_numbers_are_jumpers no)
		(fp_line
			(start 0.7874 0.4064)
			(end -0.7874 0.4064)
			(stroke
				(width 0.1524)
				(type default)
			)
			(layer "F.SilkS")
		)
		(fp_line
			(start 0.7874 -0.4064)
			(end 0.7874 0.4064)
			(stroke
				(width 0.1524)
				(type default)
			)
			(layer "F.SilkS")
		)
		(fp_line
			(start -0.7874 0.4064)
			(end -0.7874 -0.4064)
			(stroke
				(width 0.1524)
				(type default)
			)
			(layer "F.SilkS")
		)
		(fp_line
			(start -0.7874 -0.4064)
			(end 0.7874 -0.4064)
			(stroke
				(width 0.1524)
				(type default)
			)
			(layer "F.SilkS")
		)
		(fp_line
			(start 0.67945 0.3048)
			(end 0.120396 0.3048)
			(stroke
				(width 0.1)
				(type default)
			)
			(layer "F.Fab")
		)
		(fp_line
			(start 0.67945 -0.3048)
			(end 0.67945 0.3048)
			(stroke
				(width 0.1)
				(type default)
			)
			(layer "F.Fab")
		)
		(fp_line
			(start 0.12065 -0.2794)
			(end 0.12065 -0.3048)
			(stroke
				(width 0.1)
				(type default)
			)
			(layer "F.Fab")
		)
		(fp_line
			(start 0.12065 -0.3048)
			(end 0.67945 -0.3048)
			(stroke
				(width 0.1)
				(type default)
			)
			(layer "F.Fab")
		)
		(fp_line
			(start 0.120396 0.3048)
			(end 0.120396 0.2794)
			(stroke
				(width 0.1)
				(type default)
			)
			(layer "F.Fab")
		)
		(fp_line
			(start 0.120396 0.2794)
			(end -0.12065 0.2794)
			(stroke
				(width 0.1)
				(type default)
			)
			(layer "F.Fab")
		)
		(fp_line
			(start -0.12065 0.3048)
			(end -0.67945 0.3048)
			(stroke
				(width 0.1)
				(type default)
			)
			(layer "F.Fab")
		)
		(fp_line
			(start -0.12065 0.2794)
			(end -0.12065 0.3048)
			(stroke
				(width 0.1)
				(type default)
			)
			(layer "F.Fab")
		)
		(fp_line
			(start -0.12065 -0.2794)
			(end 0.12065 -0.2794)
			(stroke
				(width 0.1)
				(type default)
			)
			(layer "F.Fab")
		)
		(fp_line
			(start -0.12065 -0.305054)
			(end -0.12065 -0.2794)
			(stroke
				(width 0.1)
				(type default)
			)
			(layer "F.Fab")
		)
		(fp_line
			(start -0.67945 0.3048)
			(end -0.67945 -0.305054)
			(stroke
				(width 0.1)
				(type default)
			)
			(layer "F.Fab")
		)
		(fp_line
			(start -0.67945 -0.305054)
			(end -0.12065 -0.305054)
			(stroke
				(width 0.1)
				(type default)
			)
			(layer "F.Fab")
		)
		(pad "1" smd circle
			(at -0.40005 0 180)
			(size 0 0)
			(layers "F.Cu" "F.Mask" "F.Paste")
			(net "P3V3_AUX")
		)
		(pad "2" smd circle
			(at 0.40005 0 180)
			(size 0 0)
			(layers "F.Cu" "F.Mask" "F.Paste")
			(net "BMC_ID_BEEP_SEL")
		)
	)
	(footprint ""
		(layer "F.Cu")
		(at 26.416 -40.0304)
		(property "Reference" ""
			(at 0 0 0)
			(layer "F.SilkS")
			(hide yes)
			(effects
				(font
					(size 1.27 1.27)
				)
			)
		)
		(property "Value" ""
			(at 0 0 0)
			(layer "F.Fab")
			(effects
				(font
					(size 1.27 1.27)
				)
			)
		)
		(duplicate_pad_numbers_are_jumpers no)
		(pad "1" smd circle
			(at 0 0)
			(size 0.9906 0.9906)
			(layers "F.Cu" "F.Mask" "F.Paste")
			(net "Net_326")
		)
		(zone
			(layer "F.Cu")
			(hatch none 0.5)
			(connect_pads
				(clearance 0)
			)
			(min_thickness 0.25)
			(keepout
				(tracks not_allowed)
				(vias allowed)
				(pads allowed)
				(copperpour not_allowed)
				(footprints allowed)
			)
			(placement
				(enabled no)
				(sheetname "")
			)
			(fill
				(thermal_gap 0.5)
				(thermal_bridge_width 0.5)
				(island_removal_mode 0)
			)
			(polygon
				(pts
					(arc
						(start 28.0416 -40.0304)
						(mid 24.7904 -40.0304)
						(end 28.0416 -40.0304)
					)
				)
			)
		)
	)
	(footprint ""
		(layer "F.Cu")
		(at 76.691744 -37.559488 -90)
		(property "Reference" "R353"
			(at 0 0 270)
			(layer "F.SilkS")
			(hide yes)
			(effects
				(font
					(size 1.27 1.27)
				)
			)
		)
		(property "Value" ""
			(at 0 0 270)
			(layer "F.Fab")
			(effects
				(font
					(size 1.27 1.27)
				)
			)
		)
		(duplicate_pad_numbers_are_jumpers no)
		(fp_line
			(start -0.7874 0.4064)
			(end -0.7874 -0.4064)
			(stroke
				(width 0.1524)
				(type default)
			)
			(layer "F.SilkS")
		)
		(fp_line
			(start 0.7874 0.4064)
			(end -0.7874 0.4064)
			(stroke
				(width 0.1524)
				(type default)
			)
			(layer "F.SilkS")
		)
		(fp_line
			(start -0.7874 -0.4064)
			(end 0.7874 -0.4064)
			(stroke
				(width 0.1524)
				(type default)
			)
			(layer "F.SilkS")
		)
		(fp_line
			(start 0.7874 -0.4064)
			(end 0.7874 0.4064)
			(stroke
				(width 0.1524)
				(type default)
			)
			(layer "F.SilkS")
		)
		(fp_line
			(start -0.67945 0.3048)
			(end -0.67945 -0.305054)
			(stroke
				(width 0.1)
				(type default)
			)
			(layer "F.Fab")
		)
		(fp_line
			(start -0.12065 0.3048)
			(end -0.67945 0.3048)
			(stroke
				(width 0.1)
				(type default)
			)
			(layer "F.Fab")
		)
		(fp_line
			(start 0.120396 0.3048)
			(end 0.120396 0.2794)
			(stroke
				(width 0.1)
				(type default)
			)
			(layer "F.Fab")
		)
		(fp_line
			(start 0.67945 0.3048)
			(end 0.120396 0.3048)
			(stroke
				(width 0.1)
				(type default)
			)
			(layer "F.Fab")
		)
		(fp_line
			(start -0.12065 0.2794)
			(end -0.12065 0.3048)
			(stroke
				(width 0.1)
				(type default)
			)
			(layer "F.Fab")
		)
		(fp_line
			(start 0.120396 0.2794)
			(end -0.12065 0.2794)
			(stroke
				(width 0.1)
				(type default)
			)
			(layer "F.Fab")
		)
		(fp_line
			(start -0.12065 -0.2794)
			(end 0.12065 -0.2794)
			(stroke
				(width 0.1)
				(type default)
			)
			(layer "F.Fab")
		)
		(fp_line
			(start 0.12065 -0.2794)
			(end 0.12065 -0.3048)
			(stroke
				(width 0.1)
				(type default)
			)
			(layer "F.Fab")
		)
		(fp_line
			(start 0.12065 -0.3048)
			(end 0.67945 -0.3048)
			(stroke
				(width 0.1)
				(type default)
			)
			(layer "F.Fab")
		)
		(fp_line
			(start 0.67945 -0.3048)
			(end 0.67945 0.3048)
			(stroke
				(width 0.1)
				(type default)
			)
			(layer "F.Fab")
		)
		(fp_line
			(start -0.67945 -0.305054)
			(end -0.12065 -0.305054)
			(stroke
				(width 0.1)
				(type default)
			)
			(layer "F.Fab")
		)
		(fp_line
			(start -0.12065 -0.305054)
			(end -0.12065 -0.2794)
			(stroke
				(width 0.1)
				(type default)
			)
			(layer "F.Fab")
		)
		(pad "1" smd circle
			(at -0.40005 0 270)
			(size 0 0)
			(layers "F.Cu" "F.Mask" "F.Paste")
			(net "M_BMC_DDR4_MA<2>")
		)
		(pad "2" smd circle
			(at 0.40005 0 270)
			(size 0 0)
			(layers "F.Cu" "F.Mask" "F.Paste")
			(net "P1V2_AUX")
		)
	)
	(footprint ""
		(layer "F.Cu")
		(at 7.98322 -46.798738)
		(property "Reference" "PC210"
			(at 0 0 0)
			(layer "F.SilkS")
			(hide yes)
			(effects
				(font
					(size 1.27 1.27)
				)
			)
		)
		(property "Value" ""
			(at 0 0 0)
			(layer "F.Fab")
			(effects
				(font
					(size 1.27 1.27)
				)
			)
		)
		(duplicate_pad_numbers_are_jumpers no)
		(fp_line
			(start -0.7874 -0.4064)
			(end 0.7874 -0.4064)
			(stroke
				(width 0.1524)
				(type default)
			)
			(layer "F.SilkS")
		)
		(fp_line
			(start -0.7874 0.4064)
			(end -0.7874 -0.4064)
			(stroke
				(width 0.1524)
				(type default)
			)
			(layer "F.SilkS")
		)
		(fp_line
			(start 0.7874 -0.4064)
			(end 0.7874 0.4064)
			(stroke
				(width 0.1524)
				(type default)
			)
			(layer "F.SilkS")
		)
		(fp_line
			(start 0.7874 0.4064)
			(end -0.7874 0.4064)
			(stroke
				(width 0.1524)
				(type default)
			)
			(layer "F.SilkS")
		)
		(fp_line
			(start -0.67945 -0.305054)
			(end -0.12065 -0.305054)
			(stroke
				(width 0.1)
				(type default)
			)
			(layer "F.Fab")
		)
		(fp_line
			(start -0.67945 0.3048)
			(end -0.67945 -0.305054)
			(stroke
				(width 0.1)
				(type default)
			)
			(layer "F.Fab")
		)
		(fp_line
			(start -0.12065 -0.305054)
			(end -0.12065 -0.2794)
			(stroke
				(width 0.1)
				(type default)
			)
			(layer "F.Fab")
		)
		(fp_line
			(start -0.12065 -0.2794)
			(end 0.12065 -0.2794)
			(stroke
				(width 0.1)
				(type default)
			)
			(layer "F.Fab")
		)
		(fp_line
			(start -0.12065 0.2794)
			(end -0.12065 0.3048)
			(stroke
				(width 0.1)
				(type default)
			)
			(layer "F.Fab")
		)
		(fp_line
			(start -0.12065 0.3048)
			(end -0.67945 0.3048)
			(stroke
				(width 0.1)
				(type default)
			)
			(layer "F.Fab")
		)
		(fp_line
			(start 0.120396 0.2794)
			(end -0.12065 0.2794)
			(stroke
				(width 0.1)
				(type default)
			)
			(layer "F.Fab")
		)
		(fp_line
			(start 0.120396 0.3048)
			(end 0.120396 0.2794)
			(stroke
				(width 0.1)
				(type default)
			)
			(layer "F.Fab")
		)
		(fp_line
			(start 0.12065 -0.3048)
			(end 0.67945 -0.3048)
			(stroke
				(width 0.1)
				(type default)
			)
			(layer "F.Fab")
		)
		(fp_line
			(start 0.12065 -0.2794)
			(end 0.12065 -0.3048)
			(stroke
				(width 0.1)
				(type default)
			)
			(layer "F.Fab")
		)
		(fp_line
			(start 0.67945 -0.3048)
			(end 0.67945 0.3048)
			(stroke
				(width 0.1)
				(type default)
			)
			(layer "F.Fab")
		)
		(fp_line
			(start 0.67945 0.3048)
			(end 0.120396 0.3048)
			(stroke
				(width 0.1)
				(type default)
			)
			(layer "F.Fab")
		)
		(pad "1" smd circle
			(at -0.40005 0)
			(size 0 0)
			(layers "F.Cu" "F.Mask" "F.Paste")
			(net "SW_P5V_AUX_FLT")
		)
		(pad "2" smd circle
			(at 0.40005 0)
			(size 0 0)
			(layers "F.Cu" "F.Mask" "F.Paste")
			(net "GND")
		)
	)
	(footprint ""
		(layer "F.Cu")
		(at 4.581398 -78.196186 90)
		(property "Reference" "PC226"
			(at 0 0 90)
			(layer "F.SilkS")
			(hide yes)
			(effects
				(font
					(size 1.27 1.27)
				)
			)
		)
		(property "Value" ""
			(at 0 0 90)
			(layer "F.Fab")
			(effects
				(font
					(size 1.27 1.27)
				)
			)
		)
		(duplicate_pad_numbers_are_jumpers no)
		(fp_line
			(start 1.651 -0.8382)
			(end 1.651 0.8382)
			(stroke
				(width 0.1524)
				(type default)
			)
			(layer "F.SilkS")
		)
		(fp_line
			(start -1.651 -0.8382)
			(end 1.651 -0.8382)
			(stroke
				(width 0.1524)
				(type default)
			)
			(layer "F.SilkS")
		)
		(fp_line
			(start 1.651 0.8382)
			(end -1.651 0.8382)
			(stroke
				(width 0.1524)
				(type default)
			)
			(layer "F.SilkS")
		)
		(fp_line
			(start 0 0.8382)
			(end 0 -0.8382)
			(stroke
				(width 0.1524)
				(type default)
			)
			(layer "F.SilkS")
		)
		(fp_line
			(start -1.651 0.8382)
			(end -1.651 -0.8382)
			(stroke
				(width 0.1524)
				(type default)
			)
			(layer "F.SilkS")
		)
		(fp_line
			(start 1.55956 -0.7366)
			(end 1.524 -0.7366)
			(stroke
				(width 0.1)
				(type default)
			)
			(layer "F.Fab")
		)
		(fp_line
			(start 1.524 -0.7366)
			(end -1.524 -0.7366)
			(stroke
				(width 0.1)
				(type default)
			)
			(layer "F.Fab")
		)
		(fp_line
			(start -1.524 -0.7366)
			(end -1.55956 -0.7366)
			(stroke
				(width 0.1)
				(type default)
			)
			(layer "F.Fab")
		)
		(fp_line
			(start -1.55956 -0.7366)
			(end -1.55956 0.7366)
			(stroke
				(width 0.1)
				(type default)
			)
			(layer "F.Fab")
		)
		(fp_line
			(start 1.55956 0.7366)
			(end 1.55956 -0.7366)
			(stroke
				(width 0.1)
				(type default)
			)
			(layer "F.Fab")
		)
		(fp_line
			(start 1.524 0.7366)
			(end 1.55956 0.7366)
			(stroke
				(width 0.1)
				(type default)
			)
			(layer "F.Fab")
		)
		(fp_line
			(start -1.524 0.7366)
			(end 1.524 0.7366)
			(stroke
				(width 0.1)
				(type default)
			)
			(layer "F.Fab")
		)
		(fp_line
			(start -1.55956 0.7366)
			(end -1.524 0.7366)
			(stroke
				(width 0.1)
				(type default)
			)
			(layer "F.Fab")
		)
		(pad "1" smd rect
			(at -0.94996 0 270)
			(size 1.1176 1.3716)
			(layers "F.Cu" "F.Mask" "F.Paste")
			(net "P3V3_AUX")
		)
		(pad "2" smd rect
			(at 0.94996 0 270)
			(size 1.1176 1.3716)
			(layers "F.Cu" "F.Mask" "F.Paste")
			(net "GND")
		)
	)
)
